(kicad_pcb
	(version 20260206)
	(generator "pcbnew")
	(generator_version "10.0")
	(general
		(thickness 1.6)
		(legacy_teardrops no)
	)
	(paper "A4")
	(title_block
		(title "Wiwynn_Tioga_Pass_MB.brd")
		(comment 1 "Tioga Pass / footprints 838-844 of 4770")
	)
	(layers
		(0 "F.Cu" signal "TOP")
		(4 "In1.Cu" signal "L2GND")
		(6 "In2.Cu" signal "L3")
		(8 "In3.Cu" signal "L4GND")
		(10 "In4.Cu" signal "L5")
		(12 "In5.Cu" signal "L6GND")
		(14 "In6.Cu" signal "L7VCC")
		(16 "In7.Cu" signal "L8VCC")
		(18 "In8.Cu" signal "L9GND")
		(20 "In9.Cu" signal "L10")
		(22 "In10.Cu" signal "L11GND")
		(24 "In11.Cu" signal "L12")
		(26 "In12.Cu" signal "L13GND")
		(2 "B.Cu" signal "BOTTOM")
		(9 "F.Adhes" user "F.Adhesive")
		(11 "B.Adhes" user "B.Adhesive")
		(13 "F.Paste" user "Package Geometry/Pastemask Top")
		(15 "B.Paste" user "Package Geometry/Pastemask Bottom")
		(5 "F.SilkS" user "Ref Des/Silkscreen Top")
		(7 "B.SilkS" user "Ref Des/Silkscreen Bottom")
		(1 "F.Mask" user "Board Geometry/Soldermask Top")
		(3 "B.Mask" user "Board Geometry/Soldermask Bottom")
		(17 "Dwgs.User" user "User.Drawings")
		(19 "Cmts.User" user "User.Comments")
		(21 "Eco1.User" user "User.Eco1")
		(23 "Eco2.User" user "User.Eco2")
		(25 "Edge.Cuts" user "Board Geometry/Outline")
		(27 "Margin" user)
		(31 "F.CrtYd" user "Package Geometry/Place Bound Top")
		(29 "B.CrtYd" user "Package Geometry/Place Bound Bottom")
		(35 "F.Fab" user "Ref Des/Assembly Top")
		(33 "B.Fab" user "Ref Des/Assembly Bottom")
	)
	(footprint ""
		(layer "F.Cu")
		(at 205.486 -102.616 180)
		(property "Reference" "R4C3"
			(at 0 0 180)
			(layer "F.SilkS")
			(hide yes)
			(effects
				(font
					(size 1.27 1.27)
				)
			)
		)
		(property "Value" ""
			(at 0 0 180)
			(layer "F.Fab")
			(effects
				(font
					(size 1.27 1.27)
				)
			)
		)
		(duplicate_pad_numbers_are_jumpers no)
		(fp_poly
			(pts
				(xy -0.2794 -0.1016) (xy 0.2794 -0.1016) (xy 0.2794 0.9906) (xy -0.2794 0.9906)
			)
			(stroke
				(width 0)
				(type default)
			)
			(fill no)
			(layer "F.CrtYd")
		)
		(fp_line
			(start 0.2794 0.9906)
			(end 0.2794 -0.1016)
			(stroke
				(width 0.1)
				(type default)
			)
			(layer "F.Fab")
		)
		(fp_line
			(start 0.2794 -0.1016)
			(end -0.2794 -0.1016)
			(stroke
				(width 0.1)
				(type default)
			)
			(layer "F.Fab")
		)
		(fp_line
			(start -0.2794 0.9906)
			(end 0.2794 0.9906)
			(stroke
				(width 0.1)
				(type default)
			)
			(layer "F.Fab")
		)
		(fp_line
			(start -0.2794 -0.1016)
			(end -0.2794 0.9906)
			(stroke
				(width 0.1)
				(type default)
			)
			(layer "F.Fab")
		)
		(pad "1" smd rect
			(at 0 0 180)
			(size 0.508 0.508)
			(layers "F.Cu" "F.Mask" "F.Paste")
			(net "VSENSE_PVSA_CPU0_P")
		)
		(pad "2" smd rect
			(at 0 0.889 180)
			(size 0.508 0.508)
			(layers "F.Cu" "F.Mask" "F.Paste")
			(net "VSENSE_PVSA_CPU0_N")
		)
		(zone
			(layer "F.Cu")
			(hatch none 0.5)
			(connect_pads
				(clearance 0)
			)
			(min_thickness 0.25)
			(keepout
				(tracks not_allowed)
				(vias allowed)
				(pads allowed)
				(copperpour not_allowed)
				(footprints allowed)
			)
			(placement
				(enabled no)
				(sheetname "")
			)
			(fill
				(thermal_gap 0.5)
				(thermal_bridge_width 0.5)
				(island_removal_mode 0)
			)
			(polygon
				(pts
					(xy 205.74 -103.251) (xy 205.232 -103.251) (xy 205.232 -102.87) (xy 205.74 -102.87)
				)
			)
		)
		(zone
			(layer "F.Cu")
			(hatch none 0.5)
			(connect_pads
				(clearance 0)
			)
			(min_thickness 0.25)
			(keepout
				(tracks allowed)
				(vias not_allowed)
				(pads allowed)
				(copperpour not_allowed)
				(footprints allowed)
			)
			(placement
				(enabled no)
				(sheetname "")
			)
			(fill
				(thermal_gap 0.5)
				(thermal_bridge_width 0.5)
				(island_removal_mode 0)
			)
			(polygon
				(pts
					(xy 205.74 -102.87) (xy 205.232 -102.87) (xy 205.232 -103.251) (xy 205.74 -103.251)
				)
			)
		)
	)
	(footprint ""
		(layer "F.Cu")
		(at 266.397232 -3.3528 90)
		(property "Reference" "C5G15"
			(at 1.848866 0.752348 90)
			(unlocked yes)
			(layer "F.SilkS")
			(effects
				(font
					(size 1.27 0.9652)
					(thickness 0.1524)
				)
			)
		)
		(property "Value" ""
			(at 0 0 90)
			(layer "F.Fab")
			(effects
				(font
					(size 1.27 1.27)
				)
			)
		)
		(duplicate_pad_numbers_are_jumpers no)
		(fp_rect
			(start -0.500126 1.598422)
			(end 0.500126 -0.201422)
			(stroke
				(width 0)
				(type default)
			)
			(fill no)
			(layer "F.CrtYd")
		)
		(fp_line
			(start 0.500126 -0.201422)
			(end 0.500126 1.598422)
			(stroke
				(width 0.1)
				(type default)
			)
			(layer "F.Fab")
		)
		(fp_line
			(start -0.500126 -0.201422)
			(end 0.500126 -0.201422)
			(stroke
				(width 0.1)
				(type default)
			)
			(layer "F.Fab")
		)
		(fp_line
			(start 0.500126 1.598422)
			(end -0.500126 1.598422)
			(stroke
				(width 0.1)
				(type default)
			)
			(layer "F.Fab")
		)
		(fp_line
			(start -0.500126 1.598422)
			(end -0.500126 -0.201422)
			(stroke
				(width 0.1)
				(type default)
			)
			(layer "F.Fab")
		)
		(pad "1" smd rect
			(at 0 0)
			(size 0.889 0.9906)
			(layers "F.Cu" "F.Mask" "F.Paste")
			(net "PVDDQ_ABC")
		)
		(pad "2" smd rect
			(at 0 1.397)
			(size 0.889 0.9906)
			(layers "F.Cu" "F.Mask" "F.Paste")
			(net "GND")
		)
		(zone
			(layer "F.Cu")
			(hatch none 0.5)
			(connect_pads
				(clearance 0)
			)
			(min_thickness 0.25)
			(keepout
				(tracks not_allowed)
				(vias allowed)
				(pads allowed)
				(copperpour not_allowed)
				(footprints allowed)
			)
			(placement
				(enabled no)
				(sheetname "")
			)
			(fill
				(thermal_gap 0.5)
				(thermal_bridge_width 0.5)
				(island_removal_mode 0)
			)
			(polygon
				(pts
					(xy 267.349732 -2.8575) (xy 267.349732 -3.8481) (xy 266.841732 -3.8481) (xy 266.841732 -2.8575)
				)
			)
		)
		(zone
			(layer "F.Cu")
			(hatch none 0.5)
			(connect_pads
				(clearance 0)
			)
			(min_thickness 0.25)
			(keepout
				(tracks allowed)
				(vias not_allowed)
				(pads allowed)
				(copperpour not_allowed)
				(footprints allowed)
			)
			(placement
				(enabled no)
				(sheetname "")
			)
			(fill
				(thermal_gap 0.5)
				(thermal_bridge_width 0.5)
				(island_removal_mode 0)
			)
			(polygon
				(pts
					(xy 267.349732 -2.8575) (xy 267.349732 -3.8481) (xy 266.841732 -3.8481) (xy 266.841732 -2.8575)
				)
			)
		)
	)
	(footprint ""
		(layer "F.Cu")
		(at 324.5485 -122.555 -90)
		(property "Reference" "C827"
			(at -0.8382 -0.67818 270)
			(unlocked yes)
			(layer "F.SilkS")
			(effects
				(font
					(size 0.4064 0.254)
					(thickness 0.1524)
				)
				(justify left)
			)
		)
		(property "Value" ""
			(at 0 0 270)
			(layer "F.Fab")
			(effects
				(font
					(size 1.27 1.27)
				)
			)
		)
		(duplicate_pad_numbers_are_jumpers no)
		(fp_poly
			(pts
				(xy 0.3048 -0.1016) (xy 0.3048 0.9906) (xy -0.3048 0.9906) (xy -0.3048 -0.1016)
			)
			(stroke
				(width 0)
				(type default)
			)
			(fill no)
			(layer "F.CrtYd")
		)
		(fp_line
			(start -0.3048 0.9906)
			(end 0.3048 0.9906)
			(stroke
				(width 0.1)
				(type default)
			)
			(layer "F.Fab")
		)
		(fp_line
			(start 0.3048 0.9906)
			(end 0.3048 -0.1016)
			(stroke
				(width 0.1)
				(type default)
			)
			(layer "F.Fab")
		)
		(fp_line
			(start -0.3048 -0.1016)
			(end -0.3048 0.9906)
			(stroke
				(width 0.1)
				(type default)
			)
			(layer "F.Fab")
		)
		(fp_line
			(start 0.3048 -0.1016)
			(end -0.3048 -0.1016)
			(stroke
				(width 0.1)
				(type default)
			)
			(layer "F.Fab")
		)
		(pad "1" smd rect
			(at 0 0 270)
			(size 0.508 0.508)
			(layers "F.Cu" "F.Mask" "F.Paste")
			(net "P3E_CPU0_PE1_PCH_TXP<14>")
		)
		(pad "2" smd rect
			(at 0 0.889 270)
			(size 0.508 0.508)
			(layers "F.Cu" "F.Mask" "F.Paste")
			(net "P3E_CPU0_PE1_PCH_CON_TXP<14>")
		)
		(zone
			(layer "F.Cu")
			(hatch none 0.5)
			(connect_pads
				(clearance 0)
			)
			(min_thickness 0.25)
			(keepout
				(tracks not_allowed)
				(vias allowed)
				(pads allowed)
				(copperpour not_allowed)
				(footprints allowed)
			)
			(placement
				(enabled no)
				(sheetname "")
			)
			(fill
				(thermal_gap 0.5)
				(thermal_bridge_width 0.5)
				(island_removal_mode 0)
			)
			(polygon
				(pts
					(xy 323.9135 -122.809) (xy 323.9135 -122.301) (xy 324.2945 -122.301) (xy 324.2945 -122.809)
				)
			)
		)
		(zone
			(layer "F.Cu")
			(hatch none 0.5)
			(connect_pads
				(clearance 0)
			)
			(min_thickness 0.25)
			(keepout
				(tracks allowed)
				(vias not_allowed)
				(pads allowed)
				(copperpour not_allowed)
				(footprints allowed)
			)
			(placement
				(enabled no)
				(sheetname "")
			)
			(fill
				(thermal_gap 0.5)
				(thermal_bridge_width 0.5)
				(island_removal_mode 0)
			)
			(polygon
				(pts
					(xy 324.2945 -122.809) (xy 324.2945 -122.301) (xy 323.9135 -122.301) (xy 323.9135 -122.809)
				)
			)
		)
	)
	(footprint ""
		(layer "F.Cu")
		(at 197.162928 -85.733382 -90)
		(property "Reference" "C4D46"
			(at 0 0 270)
			(layer "F.SilkS")
			(hide yes)
			(effects
				(font
					(size 1.27 1.27)
				)
			)
		)
		(property "Value" ""
			(at 0 0 270)
			(layer "F.Fab")
			(effects
				(font
					(size 1.27 1.27)
				)
			)
		)
		(duplicate_pad_numbers_are_jumpers no)
		(fp_poly
			(pts
				(xy 0.3048 -0.1016) (xy 0.3048 0.9906) (xy -0.3048 0.9906) (xy -0.3048 -0.1016)
			)
			(stroke
				(width 0)
				(type default)
			)
			(fill no)
			(layer "F.CrtYd")
		)
		(fp_line
			(start -0.3048 0.9906)
			(end 0.3048 0.9906)
			(stroke
				(width 0.1)
				(type default)
			)
			(layer "F.Fab")
		)
		(fp_line
			(start 0.3048 0.9906)
			(end 0.3048 -0.1016)
			(stroke
				(width 0.1)
				(type default)
			)
			(layer "F.Fab")
		)
		(fp_line
			(start -0.3048 -0.1016)
			(end -0.3048 0.9906)
			(stroke
				(width 0.1)
				(type default)
			)
			(layer "F.Fab")
		)
		(fp_line
			(start 0.3048 -0.1016)
			(end -0.3048 -0.1016)
			(stroke
				(width 0.1)
				(type default)
			)
			(layer "F.Fab")
		)
		(pad "1" smd rect
			(at 0 0 270)
			(size 0.508 0.508)
			(layers "F.Cu" "F.Mask" "F.Paste")
			(net "VR_PVCCIN_CPU0_PH5_VCIN")
		)
		(pad "2" smd rect
			(at 0 0.889 270)
			(size 0.508 0.508)
			(layers "F.Cu" "F.Mask" "F.Paste")
			(net "GND")
		)
		(zone
			(layer "F.Cu")
			(hatch none 0.5)
			(connect_pads
				(clearance 0)
			)
			(min_thickness 0.25)
			(keepout
				(tracks not_allowed)
				(vias allowed)
				(pads allowed)
				(copperpour not_allowed)
				(footprints allowed)
			)
			(placement
				(enabled no)
				(sheetname "")
			)
			(fill
				(thermal_gap 0.5)
				(thermal_bridge_width 0.5)
				(island_removal_mode 0)
			)
			(polygon
				(pts
					(xy 196.527928 -85.987382) (xy 196.527928 -85.479382) (xy 196.908928 -85.479382) (xy 196.908928 -85.987382)
				)
			)
		)
		(zone
			(layer "F.Cu")
			(hatch none 0.5)
			(connect_pads
				(clearance 0)
			)
			(min_thickness 0.25)
			(keepout
				(tracks allowed)
				(vias not_allowed)
				(pads allowed)
				(copperpour not_allowed)
				(footprints allowed)
			)
			(placement
				(enabled no)
				(sheetname "")
			)
			(fill
				(thermal_gap 0.5)
				(thermal_bridge_width 0.5)
				(island_removal_mode 0)
			)
			(polygon
				(pts
					(xy 196.908928 -85.987382) (xy 196.908928 -85.479382) (xy 196.527928 -85.479382) (xy 196.527928 -85.987382)
				)
			)
		)
	)
	(footprint ""
		(layer "F.Cu")
		(at 106.982768 -79.6036 180)
		(property "Reference" "C3W4"
			(at 0.97536 0.76708 90)
			(unlocked yes)
			(layer "F.SilkS")
			(effects
				(font
					(size 0.4064 0.254)
					(thickness 0.1524)
				)
			)
		)
		(property "Value" ""
			(at 0 0 180)
			(layer "F.Fab")
			(effects
				(font
					(size 1.27 1.27)
				)
			)
		)
		(duplicate_pad_numbers_are_jumpers no)
		(fp_poly
			(pts
				(xy -0.4953 -0.2032) (xy 0.4953 -0.2032) (xy 0.4953 1.6002) (xy -0.4953 1.6002)
			)
			(stroke
				(width 0)
				(type default)
			)
			(fill no)
			(layer "F.CrtYd")
		)
		(fp_line
			(start 0.4953 1.6002)
			(end -0.4953 1.6002)
			(stroke
				(width 0.1)
				(type default)
			)
			(layer "F.Fab")
		)
		(fp_line
			(start 0.4953 -0.2032)
			(end 0.4953 1.6002)
			(stroke
				(width 0.1)
				(type default)
			)
			(layer "F.Fab")
		)
		(fp_line
			(start -0.4953 1.6002)
			(end -0.4953 -0.2032)
			(stroke
				(width 0.1)
				(type default)
			)
			(layer "F.Fab")
		)
		(fp_line
			(start -0.4953 -0.2032)
			(end 0.4953 -0.2032)
			(stroke
				(width 0.1)
				(type default)
			)
			(layer "F.Fab")
		)
		(pad "1" smd rect
			(at 0 0 180)
			(size 0.762 0.889)
			(layers "F.Cu" "F.Mask" "F.Paste")
			(net "PVCCMCP_CPU1")
		)
		(pad "2" smd rect
			(at 0 1.397 180)
			(size 0.762 0.889)
			(layers "F.Cu" "F.Mask" "F.Paste")
			(net "GND")
		)
		(zone
			(layer "F.Cu")
			(hatch none 0.5)
			(connect_pads
				(clearance 0)
			)
			(min_thickness 0.25)
			(keepout
				(tracks not_allowed)
				(vias allowed)
				(pads allowed)
				(copperpour not_allowed)
				(footprints allowed)
			)
			(placement
				(enabled no)
				(sheetname "")
			)
			(fill
				(thermal_gap 0.5)
				(thermal_bridge_width 0.5)
				(island_removal_mode 0)
			)
			(polygon
				(pts
					(xy 107.363768 -80.0481) (xy 106.601768 -80.0481) (xy 106.601768 -80.5561) (xy 107.363768 -80.5561)
				)
			)
		)
	)
	(footprint ""
		(layer "F.Cu")
		(at 127.570484 12.014454 -90)
		(property "Reference" "T1P9"
			(at 0 0 270)
			(layer "F.SilkS")
			(hide yes)
			(effects
				(font
					(size 1.27 1.27)
				)
			)
		)
		(property "Value" "*"
			(at -3.302 1.12395 270)
			(unlocked yes)
			(layer "F.Fab")
			(hide yes)
			(effects
				(font
					(size 0.889 0.889)
					(thickness 0.1524)
				)
			)
		)
		(property "Device Type" "TPAD-DIFF-4P-GP_DISCRET-GB3-TPA"
			(at -3.302 -0.40005 270)
			(unlocked yes)
			(layer "F.Fab")
			(hide yes)
			(effects
				(font
					(size 0.889 0.889)
					(thickness 0.1524)
				)
			)
		)
		(duplicate_pad_numbers_are_jumpers no)
		(fp_line
			(start -2.286 2.286)
			(end 2.286 2.286)
			(stroke
				(width 0.1524)
				(type default)
			)
			(layer "F.SilkS")
		)
		(fp_line
			(start 2.286 2.286)
			(end 2.286 -2.286)
			(stroke
				(width 0.1524)
				(type default)
			)
			(layer "F.SilkS")
		)
		(fp_line
			(start -2.286 -2.286)
			(end -2.286 2.286)
			(stroke
				(width 0.1524)
				(type default)
			)
			(layer "F.SilkS")
		)
		(fp_line
			(start 2.286 -2.286)
			(end -2.286 -2.286)
			(stroke
				(width 0.1524)
				(type default)
			)
			(layer "F.SilkS")
		)
		(fp_line
			(start -2.413 -2.413)
			(end -2.413 -1.143)
			(stroke
				(width 0.4064)
				(type default)
			)
			(layer "F.SilkS")
		)
		(fp_line
			(start -1.143 -2.413)
			(end -2.413 -2.413)
			(stroke
				(width 0.4064)
				(type default)
			)
			(layer "F.SilkS")
		)
		(fp_rect
			(start -2.54 2.54)
			(end 2.54 -2.54)
			(stroke
				(width 0)
				(type default)
			)
			(fill no)
			(layer "F.CrtYd")
		)
		(fp_rect
			(start -2.54 2.54)
			(end 2.54 -2.54)
			(stroke
				(width 0)
				(type default)
			)
			(fill no)
			(layer "F.Fab")
		)
		(pad "1" thru_hole circle
			(at -1.27 -1.27 270)
			(size 1.524 1.524)
			(drill 0.9144)
			(layers "*.Cu" "*.Mask")
			(remove_unused_layers no)
			(net "L5_73OHM_6INCH_DP")
			(clearance -0.0508)
			(thermal_gap 0.127)
			(padstack
				(mode front_inner_back)
				(layer "Inner"
					(shape circle)
					(size 1.1684 1.1684)
					(clearance 0.127)
				)
				(layer "B.Cu"
					(shape circle)
					(size 1.524 1.524)
					(clearance -0.0508)
				)
			)
		)
		(pad "2" thru_hole circle
			(at 1.27 -1.27 270)
			(size 1.524 1.524)
			(drill 0.9144)
			(layers "*.Cu" "*.Mask")
			(remove_unused_layers no)
			(net "L5_73OHM_6INCH_DN")
			(clearance -0.0508)
			(thermal_gap 0.127)
			(padstack
				(mode front_inner_back)
				(layer "Inner"
					(shape circle)
					(size 1.1684 1.1684)
					(clearance 0.127)
				)
				(layer "B.Cu"
					(shape circle)
					(size 1.524 1.524)
					(clearance -0.0508)
				)
			)
		)
		(pad "GND1" thru_hole rect
			(at -1.27 1.27 270)
			(size 1.524 1.524)
			(drill 0.9144)
			(layers "*.Cu" "*.Mask")
			(remove_unused_layers no)
			(net "GND")
			(clearance -0.0508)
			(thermal_gap 0.127)
			(padstack
				(mode front_inner_back)
				(layer "Inner"
					(shape circle)
					(size 1.1684 1.1684)
					(clearance 0.127)
				)
				(layer "B.Cu"
					(shape rect)
					(size 1.524 1.524)
					(clearance -0.0508)
				)
			)
		)
		(pad "GND2" thru_hole rect
			(at 1.27 1.27 270)
			(size 1.524 1.524)
			(drill 0.9144)
			(layers "*.Cu" "*.Mask")
			(remove_unused_layers no)
			(net "GND")
			(clearance -0.0508)
			(thermal_gap 0.127)
			(padstack
				(mode front_inner_back)
				(layer "Inner"
					(shape circle)
					(size 1.1684 1.1684)
					(clearance 0.127)
				)
				(layer "B.Cu"
					(shape rect)
					(size 1.524 1.524)
					(clearance -0.0508)
				)
			)
		)
	)
	(footprint ""
		(layer "F.Cu")
		(at 273.8628 -68.072 90)
		(property "Reference" "R5D5"
			(at 0 0 90)
			(layer "F.SilkS")
			(hide yes)
			(effects
				(font
					(size 1.27 1.27)
				)
			)
		)
		(property "Value" ""
			(at 0 0 90)
			(layer "F.Fab")
			(effects
				(font
					(size 1.27 1.27)
				)
			)
		)
		(duplicate_pad_numbers_are_jumpers no)
		(fp_poly
			(pts
				(xy -0.2794 -0.1016) (xy 0.2794 -0.1016) (xy 0.2794 0.9906) (xy -0.2794 0.9906)
			)
			(stroke
				(width 0)
				(type default)
			)
			(fill no)
			(layer "F.CrtYd")
		)
		(fp_line
			(start 0.2794 -0.1016)
			(end -0.2794 -0.1016)
			(stroke
				(width 0.1)
				(type default)
			)
			(layer "F.Fab")
		)
		(fp_line
			(start -0.2794 -0.1016)
			(end -0.2794 0.9906)
			(stroke
				(width 0.1)
				(type default)
			)
			(layer "F.Fab")
		)
		(fp_line
			(start 0.2794 0.9906)
			(end 0.2794 -0.1016)
			(stroke
				(width 0.1)
				(type default)
			)
			(layer "F.Fab")
		)
		(fp_line
			(start -0.2794 0.9906)
			(end 0.2794 0.9906)
			(stroke
				(width 0.1)
				(type default)
			)
			(layer "F.Fab")
		)
		(pad "1" smd rect
			(at 0 0 90)
			(size 0.508 0.508)
			(layers "F.Cu" "F.Mask" "F.Paste")
			(net "VSENSE_PMAX_CPU0")
		)
		(pad "2" smd rect
			(at 0 0.889 90)
			(size 0.508 0.508)
			(layers "F.Cu" "F.Mask" "F.Paste")
			(net "GND")
		)
		(zone
			(layer "F.Cu")
			(hatch none 0.5)
			(connect_pads
				(clearance 0)
			)
			(min_thickness 0.25)
			(keepout
				(tracks allowed)
				(vias not_allowed)
				(pads allowed)
				(copperpour not_allowed)
				(footprints allowed)
			)
			(placement
				(enabled no)
				(sheetname "")
			)
			(fill
				(thermal_gap 0.5)
				(thermal_bridge_width 0.5)
				(island_removal_mode 0)
			)
			(polygon
				(pts
					(xy 274.1168 -67.818) (xy 274.1168 -68.326) (xy 274.4978 -68.326) (xy 274.4978 -67.818)
				)
			)
		)
		(zone
			(layer "F.Cu")
			(hatch none 0.5)
			(connect_pads
				(clearance 0)
			)
			(min_thickness 0.25)
			(keepout
				(tracks not_allowed)
				(vias allowed)
				(pads allowed)
				(copperpour not_allowed)
				(footprints allowed)
			)
			(placement
				(enabled no)
				(sheetname "")
			)
			(fill
				(thermal_gap 0.5)
				(thermal_bridge_width 0.5)
				(island_removal_mode 0)
			)
			(polygon
				(pts
					(xy 274.4978 -67.818) (xy 274.4978 -68.326) (xy 274.1168 -68.326) (xy 274.1168 -67.818)
				)
			)
		)
	)
)
